# S9S_MB_2U (Grand Teton) — schematic netlist excerpt (pin names and nets, part order shuffled) for the footprints in the layout excerpt that follows; sources: Cadence DE-HDL packaged netlist, KiCad conversion of 03242023_DA0F0TMBIJ0_F0T_Motherboard_J_brd_V01_OCP.brd

R4551  Q_RES  54.9K 1% EMPTY  pkg 0402LF  page 246 : A = P3V3_AUX ; B = HPDB_HSC_PWRGD
R4151  Q_RES  33.2 1% CHIP  pkg 0402LF  page 241 : A = SMB_1_PLD_3V3AUX_SCL ; B = SMB_2_PLD_3V3AUX_SCL_R1

(kicad_pcb
	(version 20260206)
	(generator "pcbnew")
	(generator_version "10.0")
	(general
		(thickness 1.6)
		(legacy_teardrops no)
	)
	(paper "A4")
	(title_block
		(title "03242023_DA0F0TMBIJ0_F0T_Motherboard_J_brd_V01_OCP.brd")
		(comment 1 "Grand Teton / footprints 4144-4145 of 6105")
	)
	(layers
		(0 "F.Cu" signal "TOP")
		(4 "In1.Cu" signal "GND")
		(6 "In2.Cu" signal "IN1")
		(8 "In3.Cu" signal "GND1")
		(10 "In4.Cu" signal "IN2")
		(12 "In5.Cu" signal "GND2")
		(14 "In6.Cu" signal "IN3")
		(16 "In7.Cu" signal "GND3")
		(18 "In8.Cu" signal "VCC")
		(20 "In9.Cu" signal "VCC1")
		(22 "In10.Cu" signal "GND4")
		(24 "In11.Cu" signal "IN4")
		(26 "In12.Cu" signal "GND5")
		(28 "In13.Cu" signal "IN5")
		(30 "In14.Cu" signal "GND6")
		(32 "In15.Cu" signal "IN6")
		(34 "In16.Cu" signal "GND7")
		(2 "B.Cu" signal "BOTTOM")
		(9 "F.Adhes" user "F.Adhesive")
		(11 "B.Adhes" user "B.Adhesive")
		(13 "F.Paste" user "Package Geometry/Pastemask Top")
		(15 "B.Paste" user "Package Geometry/Pastemask Bottom")
		(5 "F.SilkS" user "Ref Des/Silkscreen Top")
		(7 "B.SilkS" user "Ref Des/Silkscreen Bottom")
		(1 "F.Mask" user "Board Geometry/Soldermask Top")
		(3 "B.Mask" user "Board Geometry/Soldermask Bottom")
		(17 "Dwgs.User" user "User.Drawings")
		(19 "Cmts.User" user "User.Comments")
		(21 "Eco1.User" user "User.Eco1")
		(23 "Eco2.User" user "User.Eco2")
		(25 "Edge.Cuts" user "Board Geometry/Outline")
		(27 "Margin" user)
		(31 "F.CrtYd" user "Package Geometry/Place Bound Top")
		(29 "B.CrtYd" user "Package Geometry/Place Bound Bottom")
		(35 "F.Fab" user "Ref Des/Assembly Top")
		(33 "B.Fab" user "Ref Des/Assembly Bottom")
	)
	(footprint ""
		(layer "F.Cu")
		(at 284.589728 -413.23768 -90)
		(property "Reference" "R4551"
			(at 0 0 270)
			(layer "F.SilkS")
			(hide yes)
			(effects
				(font
					(size 1.27 1.27)
				)
			)
		)
		(property "Value" ""
			(at 0 0 270)
			(layer "F.Fab")
			(effects
				(font
					(size 1.27 1.27)
				)
			)
		)
		(duplicate_pad_numbers_are_jumpers no)
		(fp_line
			(start -0.7874 0.4064)
			(end -0.7874 -0.4064)
			(stroke
				(width 0.1524)
				(type default)
			)
			(layer "F.SilkS")
		)
		(fp_line
			(start 0.7874 0.4064)
			(end -0.7874 0.4064)
			(stroke
				(width 0.1524)
				(type default)
			)
			(layer "F.SilkS")
		)
		(fp_line
			(start -0.7874 -0.4064)
			(end 0.7874 -0.4064)
			(stroke
				(width 0.1524)
				(type default)
			)
			(layer "F.SilkS")
		)
		(fp_line
			(start 0.7874 -0.4064)
			(end 0.7874 0.4064)
			(stroke
				(width 0.1524)
				(type default)
			)
			(layer "F.SilkS")
		)
		(fp_line
			(start -0.67945 0.3048)
			(end -0.67945 -0.305054)
			(stroke
				(width 0.1)
				(type default)
			)
			(layer "F.Fab")
		)
		(fp_line
			(start -0.12065 0.3048)
			(end -0.67945 0.3048)
			(stroke
				(width 0.1)
				(type default)
			)
			(layer "F.Fab")
		)
		(fp_line
			(start 0.120396 0.3048)
			(end 0.120396 0.2794)
			(stroke
				(width 0.1)
				(type default)
			)
			(layer "F.Fab")
		)
		(fp_line
			(start 0.67945 0.3048)
			(end 0.120396 0.3048)
			(stroke
				(width 0.1)
				(type default)
			)
			(layer "F.Fab")
		)
		(fp_line
			(start -0.12065 0.2794)
			(end -0.12065 0.3048)
			(stroke
				(width 0.1)
				(type default)
			)
			(layer "F.Fab")
		)
		(fp_line
			(start 0.120396 0.2794)
			(end -0.12065 0.2794)
			(stroke
				(width 0.1)
				(type default)
			)
			(layer "F.Fab")
		)
		(fp_line
			(start -0.12065 -0.2794)
			(end 0.12065 -0.2794)
			(stroke
				(width 0.1)
				(type default)
			)
			(layer "F.Fab")
		)
		(fp_line
			(start 0.12065 -0.2794)
			(end 0.12065 -0.3048)
			(stroke
				(width 0.1)
				(type default)
			)
			(layer "F.Fab")
		)
		(fp_line
			(start 0.12065 -0.3048)
			(end 0.67945 -0.3048)
			(stroke
				(width 0.1)
				(type default)
			)
			(layer "F.Fab")
		)
		(fp_line
			(start 0.67945 -0.3048)
			(end 0.67945 0.3048)
			(stroke
				(width 0.1)
				(type default)
			)
			(layer "F.Fab")
		)
		(fp_line
			(start -0.67945 -0.305054)
			(end -0.12065 -0.305054)
			(stroke
				(width 0.1)
				(type default)
			)
			(layer "F.Fab")
		)
		(fp_line
			(start -0.12065 -0.305054)
			(end -0.12065 -0.2794)
			(stroke
				(width 0.1)
				(type default)
			)
			(layer "F.Fab")
		)
		(pad "1" smd circle
			(at -0.40005 0 270)
			(size 0 0)
			(layers "F.Cu" "F.Mask" "F.Paste")
			(net "P3V3_AUX")
		)
		(pad "2" smd circle
			(at 0.40005 0 270)
			(size 0 0)
			(layers "F.Cu" "F.Mask" "F.Paste")
			(net "HPDB_HSC_PWRGD")
		)
	)
	(footprint ""
		(layer "F.Cu")
		(at 162.573462 -22.36089)
		(property "Reference" "R4151"
			(at 0 0 0)
			(layer "F.SilkS")
			(hide yes)
			(effects
				(font
					(size 1.27 1.27)
				)
			)
		)
		(property "Value" ""
			(at 0 0 0)
			(layer "F.Fab")
			(effects
				(font
					(size 1.27 1.27)
				)
			)
		)
		(duplicate_pad_numbers_are_jumpers no)
		(fp_line
			(start -0.7874 -0.4064)
			(end 0.7874 -0.4064)
			(stroke
				(width 0.1524)
				(type default)
			)
			(layer "F.SilkS")
		)
		(fp_line
			(start -0.7874 0.4064)
			(end -0.7874 -0.4064)
			(stroke
				(width 0.1524)
				(type default)
			)
			(layer "F.SilkS")
		)
		(fp_line
			(start 0.7874 -0.4064)
			(end 0.7874 0.4064)
			(stroke
				(width 0.1524)
				(type default)
			)
			(layer "F.SilkS")
		)
		(fp_line
			(start 0.7874 0.4064)
			(end -0.7874 0.4064)
			(stroke
				(width 0.1524)
				(type default)
			)
			(layer "F.SilkS")
		)
		(fp_line
			(start -0.67945 -0.305054)
			(end -0.12065 -0.305054)
			(stroke
				(width 0.1)
				(type default)
			)
			(layer "F.Fab")
		)
		(fp_line
			(start -0.67945 0.3048)
			(end -0.67945 -0.305054)
			(stroke
				(width 0.1)
				(type default)
			)
			(layer "F.Fab")
		)
		(fp_line
			(start -0.12065 -0.305054)
			(end -0.12065 -0.2794)
			(stroke
				(width 0.1)
				(type default)
			)
			(layer "F.Fab")
		)
		(fp_line
			(start -0.12065 -0.2794)
			(end 0.12065 -0.2794)
			(stroke
				(width 0.1)
				(type default)
			)
			(layer "F.Fab")
		)
		(fp_line
			(start -0.12065 0.2794)
			(end -0.12065 0.3048)
			(stroke
				(width 0.1)
				(type default)
			)
			(layer "F.Fab")
		)
		(fp_line
			(start -0.12065 0.3048)
			(end -0.67945 0.3048)
			(stroke
				(width 0.1)
				(type default)
			)
			(layer "F.Fab")
		)
		(fp_line
			(start 0.120396 0.2794)
			(end -0.12065 0.2794)
			(stroke
				(width 0.1)
				(type default)
			)
			(layer "F.Fab")
		)
		(fp_line
			(start 0.120396 0.3048)
			(end 0.120396 0.2794)
			(stroke
				(width 0.1)
				(type default)
			)
			(layer "F.Fab")
		)
		(fp_line
			(start 0.12065 -0.3048)
			(end 0.67945 -0.3048)
			(stroke
				(width 0.1)
				(type default)
			)
			(layer "F.Fab")
		)
		(fp_line
			(start 0.12065 -0.2794)
			(end 0.12065 -0.3048)
			(stroke
				(width 0.1)
				(type default)
			)
			(layer "F.Fab")
		)
		(fp_line
			(start 0.67945 -0.3048)
			(end 0.67945 0.3048)
			(stroke
				(width 0.1)
				(type default)
			)
			(layer "F.Fab")
		)
		(fp_line
			(start 0.67945 0.3048)
			(end 0.120396 0.3048)
			(stroke
				(width 0.1)
				(type default)
			)
			(layer "F.Fab")
		)
		(pad "1" smd circle
			(at -0.40005 0)
			(size 0 0)
			(layers "F.Cu" "F.Mask" "F.Paste")
			(net "SMB_1_PLD_3V3AUX_SCL")
		)
		(pad "2" smd circle
			(at 0.40005 0)
			(size 0 0)
			(layers "F.Cu" "F.Mask" "F.Paste")
			(net "SMB_2_PLD_3V3AUX_SCL_R1")
		)
	)
)
